(kicad_pcb
	(version 20260206)
	(generator "pcbnew")
	(generator_version "10.0")
	(general
		(thickness 1.6)
		(legacy_teardrops no)
	)
	(paper "A4")
	(title_block
		(title "pdpb — Lightning_PDPB_BRD.brd")
		(comment 1 "Lightning (Wiwynn / Facebook NVMe JBOF) / footprints 897-903 of 1140")
	)
	(layers
		(0 "F.Cu" signal "TOP")
		(4 "In1.Cu" signal "L2GND")
		(6 "In2.Cu" signal "L3")
		(8 "In3.Cu" signal "L4VCC")
		(10 "In4.Cu" signal "L5VCC")
		(12 "In5.Cu" signal "L6")
		(14 "In6.Cu" signal "L7GND")
		(2 "B.Cu" signal "BOTTOM")
		(9 "F.Adhes" user "F.Adhesive")
		(11 "B.Adhes" user "B.Adhesive")
		(13 "F.Paste" user "Package Geometry/Pastemask Top")
		(15 "B.Paste" user "Package Geometry/Pastemask Bottom")
		(5 "F.SilkS" user "Ref Des/Silkscreen Top")
		(7 "B.SilkS" user "Ref Des/Silkscreen Bottom")
		(1 "F.Mask" user "Board Geometry/Soldermask Top")
		(3 "B.Mask" user "Board Geometry/Soldermask Bottom")
		(17 "Dwgs.User" user "User.Drawings")
		(19 "Cmts.User" user "User.Comments")
		(21 "Eco1.User" user "User.Eco1")
		(23 "Eco2.User" user "User.Eco2")
		(25 "Edge.Cuts" user "Board Geometry/Outline")
		(27 "Margin" user)
		(31 "F.CrtYd" user "Package Geometry/Place Bound Top")
		(29 "B.CrtYd" user "Package Geometry/Place Bound Bottom")
		(35 "F.Fab" user "Ref Des/Assembly Top")
		(33 "B.Fab" user "Ref Des/Assembly Bottom")
	)
	(footprint ""
		(layer "F.Cu")
		(at 8.053578 -272.298414 180)
		(property "Reference" "R584"
			(at 0 0 180)
			(layer "F.SilkS")
			(hide yes)
			(effects
				(font
					(size 1.27 1.27)
				)
			)
		)
		(property "Value" "2R2010J-1-GP"
			(at 0.254 -8.0772 180)
			(unlocked yes)
			(layer "F.Fab")
			(hide yes)
			(effects
				(font
					(size 1.016 1.016)
					(thickness 0.1524)
				)
			)
		)
		(property "Device Type" "R2010H28"
			(at 0.254 -9.6774 180)
			(unlocked yes)
			(layer "F.Fab")
			(hide yes)
			(effects
				(font
					(size 1.016 1.016)
					(thickness 0.1524)
				)
			)
		)
		(duplicate_pad_numbers_are_jumpers no)
		(fp_line
			(start 1.651 3.302)
			(end 1.651 -3.302)
			(stroke
				(width 0.1524)
				(type default)
			)
			(layer "F.SilkS")
		)
		(fp_line
			(start 1.651 -3.302)
			(end -1.651 -3.302)
			(stroke
				(width 0.1524)
				(type default)
			)
			(layer "F.SilkS")
		)
		(fp_line
			(start -1.651 3.302)
			(end 1.651 3.302)
			(stroke
				(width 0.1524)
				(type default)
			)
			(layer "F.SilkS")
		)
		(fp_line
			(start -1.651 -3.302)
			(end -1.651 3.302)
			(stroke
				(width 0.1524)
				(type default)
			)
			(layer "F.SilkS")
		)
		(fp_rect
			(start -1.7272 -3.3782)
			(end 1.7272 3.3782)
			(stroke
				(width 0)
				(type default)
			)
			(fill no)
			(layer "F.CrtYd")
		)
		(fp_poly
			(pts
				(xy 1.7272 3.3782) (xy 1.7272 -3.3782) (xy -1.7272 -3.3782) (xy -1.7272 3.3782)
			)
			(stroke
				(width 0)
				(type default)
			)
			(fill no)
			(layer "F.Fab")
		)
		(pad "1" smd rect
			(at 0 -2.3495 180)
			(size 2.794 1.143)
			(layers "F.Cu" "F.Mask" "F.Paste")
			(net "PCIE_MATED#_B")
		)
		(pad "2" smd rect
			(at 0 2.3495 180)
			(size 2.794 1.143)
			(layers "F.Cu" "F.Mask" "F.Paste")
			(net "GND")
		)
	)
	(footprint ""
		(layer "F.Cu")
		(at 22.247606 -162.109658 180)
		(property "Reference" "R9868"
			(at 0 0 180)
			(layer "F.SilkS")
			(hide yes)
			(effects
				(font
					(size 1.27 1.27)
				)
			)
		)
		(property "Value" "0R2J-2-GP"
			(at 0.064008 -3.993896 180)
			(unlocked yes)
			(layer "F.Fab")
			(hide yes)
			(effects
				(font
					(size 1.016 1.016)
					(thickness 0.1524)
				)
			)
		)
		(property "Device Type" "R402H16"
			(at 0.064008 -5.517896 180)
			(unlocked yes)
			(layer "F.Fab")
			(hide yes)
			(effects
				(font
					(size 1.016 1.016)
					(thickness 0.1524)
				)
			)
		)
		(duplicate_pad_numbers_are_jumpers no)
		(fp_line
			(start 0.508 -0.9398)
			(end -0.508 -0.9398)
			(stroke
				(width 0.1524)
				(type default)
			)
			(layer "F.SilkS")
		)
		(fp_line
			(start -0.508 -0.9398)
			(end -0.508 0.9398)
			(stroke
				(width 0.1524)
				(type default)
			)
			(layer "F.SilkS")
		)
		(fp_rect
			(start -0.508 0.9398)
			(end 0.508 -0.9398)
			(stroke
				(width 0)
				(type default)
			)
			(fill no)
			(layer "F.CrtYd")
		)
		(fp_rect
			(start -0.508 0.9398)
			(end 0.508 -0.9398)
			(stroke
				(width 0)
				(type default)
			)
			(fill no)
			(layer "F.Fab")
		)
		(pad "1" smd custom
			(at 0 -0.4445 180)
			(size 0.1397 0.1397)
			(layers "F.Cu" "F.Mask" "F.Paste")
			(net "ATTN_LED_DR13_R")
			(options
				(clearance outline)
				(anchor circle)
			)
			(primitives
				(gr_poly
					(pts
						(arc
							(start -0.1778 -0.2794)
							(mid -0.249642 -0.249642)
							(end -0.2794 -0.1778)
						)
						(arc
							(start -0.2794 0.1778)
							(mid -0.249642 0.249642)
							(end -0.1778 0.2794)
						)
						(arc
							(start 0.1778 0.2794)
							(mid 0.249642 0.249642)
							(end 0.2794 0.1778)
						)
						(arc
							(start 0.2794 -0.1778)
							(mid 0.249642 -0.249642)
							(end 0.1778 -0.2794)
						)
					)
					(width 0)
					(fill yes)
				)
			)
		)
		(pad "2" smd custom
			(at 0 0.4445 180)
			(size 0.1397 0.1397)
			(layers "F.Cu" "F.Mask" "F.Paste")
			(net "ATTN_LED_DR13_N")
			(options
				(clearance outline)
				(anchor circle)
			)
			(primitives
				(gr_poly
					(pts
						(arc
							(start -0.1778 -0.2794)
							(mid -0.249642 -0.249642)
							(end -0.2794 -0.1778)
						)
						(arc
							(start -0.2794 0.1778)
							(mid -0.249642 0.249642)
							(end -0.1778 0.2794)
						)
						(arc
							(start 0.1778 0.2794)
							(mid 0.249642 0.249642)
							(end 0.2794 0.1778)
						)
						(arc
							(start 0.2794 -0.1778)
							(mid 0.249642 -0.249642)
							(end 0.1778 -0.2794)
						)
					)
					(width 0)
					(fill yes)
				)
			)
		)
	)
	(footprint ""
		(layer "F.Cu")
		(at 90.297 -423.164)
		(property "Reference" "R9068"
			(at 0 0 0)
			(layer "F.SilkS")
			(hide yes)
			(effects
				(font
					(size 1.27 1.27)
				)
			)
		)
		(property "Value" "27R2F-GP"
			(at 0.064008 -3.993896 0)
			(unlocked yes)
			(layer "F.Fab")
			(hide yes)
			(effects
				(font
					(size 1.016 1.016)
					(thickness 0.1524)
				)
			)
		)
		(property "Device Type" "R402H16"
			(at 0.064008 -5.517896 0)
			(unlocked yes)
			(layer "F.Fab")
			(hide yes)
			(effects
				(font
					(size 1.016 1.016)
					(thickness 0.1524)
				)
			)
		)
		(duplicate_pad_numbers_are_jumpers no)
		(fp_line
			(start -0.508 -0.9398)
			(end -0.508 0.9398)
			(stroke
				(width 0.1524)
				(type default)
			)
			(layer "F.SilkS")
		)
		(fp_line
			(start 0.508 -0.9398)
			(end -0.508 -0.9398)
			(stroke
				(width 0.1524)
				(type default)
			)
			(layer "F.SilkS")
		)
		(fp_rect
			(start -0.508 0.9398)
			(end 0.508 -0.9398)
			(stroke
				(width 0)
				(type default)
			)
			(fill no)
			(layer "F.CrtYd")
		)
		(fp_rect
			(start -0.508 0.9398)
			(end 0.508 -0.9398)
			(stroke
				(width 0)
				(type default)
			)
			(fill no)
			(layer "F.Fab")
		)
		(pad "1" smd custom
			(at 0 -0.4445)
			(size 0.1397 0.1397)
			(layers "F.Cu" "F.Mask" "F.Paste")
			(net "PE_CLK_100M_DR10_1_R_P")
			(options
				(clearance outline)
				(anchor circle)
			)
			(primitives
				(gr_poly
					(pts
						(arc
							(start -0.1778 -0.2794)
							(mid -0.249642 -0.249642)
							(end -0.2794 -0.1778)
						)
						(arc
							(start -0.2794 0.1778)
							(mid -0.249642 0.249642)
							(end -0.1778 0.2794)
						)
						(arc
							(start 0.1778 0.2794)
							(mid 0.249642 0.249642)
							(end 0.2794 0.1778)
						)
						(arc
							(start 0.2794 -0.1778)
							(mid 0.249642 -0.249642)
							(end 0.1778 -0.2794)
						)
					)
					(width 0)
					(fill yes)
				)
			)
		)
		(pad "2" smd custom
			(at 0 0.4445)
			(size 0.1397 0.1397)
			(layers "F.Cu" "F.Mask" "F.Paste")
			(net "PE_CLK100M_DR10_1_P")
			(options
				(clearance outline)
				(anchor circle)
			)
			(primitives
				(gr_poly
					(pts
						(arc
							(start -0.1778 -0.2794)
							(mid -0.249642 -0.249642)
							(end -0.2794 -0.1778)
						)
						(arc
							(start -0.2794 0.1778)
							(mid -0.249642 0.249642)
							(end -0.1778 0.2794)
						)
						(arc
							(start 0.1778 0.2794)
							(mid 0.249642 0.249642)
							(end 0.2794 0.1778)
						)
						(arc
							(start 0.2794 -0.1778)
							(mid 0.249642 -0.249642)
							(end 0.1778 -0.2794)
						)
					)
					(width 0)
					(fill yes)
				)
			)
		)
	)
	(footprint ""
		(layer "F.Cu")
		(at 8.7376 -463.0928 90)
		(property "Reference" "PC1165"
			(at 0 0 90)
			(layer "F.SilkS")
			(hide yes)
			(effects
				(font
					(size 1.27 1.27)
				)
			)
		)
		(property "Value" "SCD01U50V2KX-1GP"
			(at 1.1811 -2.7051 90)
			(unlocked yes)
			(layer "F.Fab")
			(hide yes)
			(effects
				(font
					(size 1.016 1.016)
					(thickness 0.1524)
				)
			)
		)
		(property "Device Type" "C402H22"
			(at 1.1811 -4.2291 90)
			(unlocked yes)
			(layer "F.Fab")
			(hide yes)
			(effects
				(font
					(size 1.016 1.016)
					(thickness 0.1524)
				)
			)
		)
		(duplicate_pad_numbers_are_jumpers no)
		(fp_rect
			(start -0.4318 0.9525)
			(end 0.4318 -0.9525)
			(stroke
				(width 0)
				(type default)
			)
			(fill no)
			(layer "F.CrtYd")
		)
		(fp_rect
			(start -0.4318 0.9525)
			(end 0.4318 -0.9525)
			(stroke
				(width 0)
				(type default)
			)
			(fill no)
			(layer "F.Fab")
		)
		(pad "1" smd custom
			(at 0 -0.4445 90)
			(size 0.1524 0.1524)
			(layers "F.Cu" "F.Mask" "F.Paste")
			(net "P12V")
			(options
				(clearance outline)
				(anchor circle)
			)
			(primitives
				(gr_poly
					(pts
						(arc
							(start 0.3048 -0.2032)
							(mid 0.275042 -0.275042)
							(end 0.2032 -0.3048)
						)
						(arc
							(start -0.2032 -0.3048)
							(mid -0.275042 -0.275042)
							(end -0.3048 -0.2032)
						)
						(arc
							(start -0.3048 0.2032)
							(mid -0.275042 0.275042)
							(end -0.2032 0.3048)
						)
						(arc
							(start 0.2032 0.3048)
							(mid 0.275042 0.275042)
							(end 0.3048 0.2032)
						)
					)
					(width 0)
					(fill yes)
				)
			)
		)
		(pad "2" smd custom
			(at 0 0.4445 90)
			(size 0.1524 0.1524)
			(layers "F.Cu" "F.Mask" "F.Paste")
			(net "GND")
			(options
				(clearance outline)
				(anchor circle)
			)
			(primitives
				(gr_poly
					(pts
						(arc
							(start 0.3048 -0.2032)
							(mid 0.275042 -0.275042)
							(end 0.2032 -0.3048)
						)
						(arc
							(start -0.2032 -0.3048)
							(mid -0.275042 -0.275042)
							(end -0.3048 -0.2032)
						)
						(arc
							(start -0.3048 0.2032)
							(mid -0.275042 0.275042)
							(end -0.2032 0.3048)
						)
						(arc
							(start 0.2032 0.3048)
							(mid 0.275042 0.275042)
							(end 0.3048 0.2032)
						)
					)
					(width 0)
					(fill yes)
				)
			)
		)
	)
	(footprint ""
		(layer "F.Cu")
		(at 37.973 -205.74 180)
		(property "Reference" "R9772"
			(at 0 0 180)
			(layer "F.SilkS")
			(hide yes)
			(effects
				(font
					(size 1.27 1.27)
				)
			)
		)
		(property "Value" "4K7R2J-2-GP"
			(at 0.064008 -3.993896 180)
			(unlocked yes)
			(layer "F.Fab")
			(hide yes)
			(effects
				(font
					(size 1.016 1.016)
					(thickness 0.1524)
				)
			)
		)
		(property "Device Type" "R402H16"
			(at 0.064008 -5.517896 180)
			(unlocked yes)
			(layer "F.Fab")
			(hide yes)
			(effects
				(font
					(size 1.016 1.016)
					(thickness 0.1524)
				)
			)
		)
		(duplicate_pad_numbers_are_jumpers no)
		(fp_line
			(start 0.508 -0.9398)
			(end -0.508 -0.9398)
			(stroke
				(width 0.1524)
				(type default)
			)
			(layer "F.SilkS")
		)
		(fp_line
			(start -0.508 -0.9398)
			(end -0.508 0.9398)
			(stroke
				(width 0.1524)
				(type default)
			)
			(layer "F.SilkS")
		)
		(fp_rect
			(start -0.508 0.9398)
			(end 0.508 -0.9398)
			(stroke
				(width 0)
				(type default)
			)
			(fill no)
			(layer "F.CrtYd")
		)
		(fp_rect
			(start -0.508 0.9398)
			(end 0.508 -0.9398)
			(stroke
				(width 0)
				(type default)
			)
			(fill no)
			(layer "F.Fab")
		)
		(pad "1" smd custom
			(at 0 -0.4445 180)
			(size 0.1397 0.1397)
			(layers "F.Cu" "F.Mask" "F.Paste")
			(net "SSD12_PWREN")
			(options
				(clearance outline)
				(anchor circle)
			)
			(primitives
				(gr_poly
					(pts
						(arc
							(start -0.1778 -0.2794)
							(mid -0.249642 -0.249642)
							(end -0.2794 -0.1778)
						)
						(arc
							(start -0.2794 0.1778)
							(mid -0.249642 0.249642)
							(end -0.1778 0.2794)
						)
						(arc
							(start 0.1778 0.2794)
							(mid 0.249642 0.249642)
							(end 0.2794 0.1778)
						)
						(arc
							(start 0.2794 -0.1778)
							(mid 0.249642 -0.249642)
							(end 0.1778 -0.2794)
						)
					)
					(width 0)
					(fill yes)
				)
			)
		)
		(pad "2" smd custom
			(at 0 0.4445 180)
			(size 0.1397 0.1397)
			(layers "F.Cu" "F.Mask" "F.Paste")
			(net "GND")
			(options
				(clearance outline)
				(anchor circle)
			)
			(primitives
				(gr_poly
					(pts
						(arc
							(start -0.1778 -0.2794)
							(mid -0.249642 -0.249642)
							(end -0.2794 -0.1778)
						)
						(arc
							(start -0.2794 0.1778)
							(mid -0.249642 0.249642)
							(end -0.1778 0.2794)
						)
						(arc
							(start 0.1778 0.2794)
							(mid 0.249642 0.249642)
							(end 0.2794 0.1778)
						)
						(arc
							(start 0.2794 -0.1778)
							(mid 0.249642 -0.249642)
							(end 0.1778 -0.2794)
						)
					)
					(width 0)
					(fill yes)
				)
			)
		)
	)
	(footprint ""
		(layer "F.Cu")
		(at 17.9578 -499.1608 -90)
		(property "Reference" "Q51"
			(at 0 0 270)
			(layer "F.SilkS")
			(hide yes)
			(effects
				(font
					(size 1.27 1.27)
				)
			)
		)
		(property "Value" "2N7002A-7-GP"
			(at 0.127 -8.9662 270)
			(unlocked yes)
			(layer "F.Fab")
			(hide yes)
			(effects
				(font
					(size 1.016 1.016)
					(thickness 0.1524)
				)
			)
		)
		(property "Device Type" "SOT23DGS2D4H48"
			(at 0.127 -10.4902 270)
			(unlocked yes)
			(layer "F.Fab")
			(hide yes)
			(effects
				(font
					(size 1.016 1.016)
					(thickness 0.1524)
				)
			)
		)
		(duplicate_pad_numbers_are_jumpers no)
		(fp_line
			(start -1.651 1.778)
			(end 1.651 1.778)
			(stroke
				(width 0.1524)
				(type default)
			)
			(layer "F.SilkS")
		)
		(fp_line
			(start 1.651 1.778)
			(end 1.651 -1.778)
			(stroke
				(width 0.1524)
				(type default)
			)
			(layer "F.SilkS")
		)
		(fp_line
			(start -1.651 -1.778)
			(end -1.651 1.778)
			(stroke
				(width 0.1524)
				(type default)
			)
			(layer "F.SilkS")
		)
		(fp_line
			(start 1.651 -1.778)
			(end -1.651 -1.778)
			(stroke
				(width 0.1524)
				(type default)
			)
			(layer "F.SilkS")
		)
		(fp_poly
			(pts
				(xy -1.778 1.8796) (xy -1.778 -1.8796) (xy 1.778 -1.8796) (xy 1.778 1.8796)
			)
			(stroke
				(width 0)
				(type default)
			)
			(fill no)
			(layer "F.CrtYd")
		)
		(fp_poly
			(pts
				(xy -1.778 1.8796) (xy -1.778 -1.8796) (xy 1.778 -1.8796) (xy 1.778 1.8796)
			)
			(stroke
				(width 0)
				(type default)
			)
			(fill no)
			(layer "F.Fab")
		)
		(pad "D" smd custom
			(at 0 -0.9525 270)
			(size 0.1905 0.1905)
			(layers "F.Cu" "F.Mask" "F.Paste")
			(net "P12V_MOST5_GATE_D")
			(options
				(clearance outline)
				(anchor circle)
			)
			(primitives
				(gr_poly
					(pts
						(arc
							(start -0.1778 0.5715)
							(mid -0.321484 0.511984)
							(end -0.381 0.3683)
						)
						(arc
							(start -0.381 -0.3683)
							(mid -0.321484 -0.511984)
							(end -0.1778 -0.5715)
						)
						(arc
							(start 0.1778 -0.5715)
							(mid 0.321484 -0.511984)
							(end 0.381 -0.3683)
						)
						(arc
							(start 0.381 0.3683)
							(mid 0.321484 0.511984)
							(end 0.1778 0.5715)
						)
					)
					(width 0)
					(fill yes)
				)
			)
		)
		(pad "G" smd custom
			(at -0.98425 0.9525 270)
			(size 0.1905 0.1905)
			(layers "F.Cu" "F.Mask" "F.Paste")
			(net "P12V_MOST5_GATE")
			(options
				(clearance outline)
				(anchor circle)
			)
			(primitives
				(gr_poly
					(pts
						(arc
							(start -0.1778 0.5715)
							(mid -0.321484 0.511984)
							(end -0.381 0.3683)
						)
						(arc
							(start -0.381 -0.3683)
							(mid -0.321484 -0.511984)
							(end -0.1778 -0.5715)
						)
						(arc
							(start 0.1778 -0.5715)
							(mid 0.321484 -0.511984)
							(end 0.381 -0.3683)
						)
						(arc
							(start 0.381 0.3683)
							(mid 0.321484 0.511984)
							(end 0.1778 0.5715)
						)
					)
					(width 0)
					(fill yes)
				)
			)
		)
		(pad "S" smd custom
			(at 0.98425 0.9525 270)
			(size 0.1905 0.1905)
			(layers "F.Cu" "F.Mask" "F.Paste")
			(net "GND")
			(options
				(clearance outline)
				(anchor circle)
			)
			(primitives
				(gr_poly
					(pts
						(arc
							(start -0.1778 0.5715)
							(mid -0.321484 0.511984)
							(end -0.381 0.3683)
						)
						(arc
							(start -0.381 -0.3683)
							(mid -0.321484 -0.511984)
							(end -0.1778 -0.5715)
						)
						(arc
							(start 0.1778 -0.5715)
							(mid 0.321484 -0.511984)
							(end 0.381 -0.3683)
						)
						(arc
							(start 0.381 0.3683)
							(mid 0.321484 0.511984)
							(end 0.1778 0.5715)
						)
					)
					(width 0)
					(fill yes)
				)
			)
		)
	)
	(footprint ""
		(layer "F.Cu")
		(at 82.931 -214.122 -90)
		(property "Reference" "PR9063"
			(at 0 0 270)
			(layer "F.SilkS")
			(hide yes)
			(effects
				(font
					(size 1.27 1.27)
				)
			)
		)
		(property "Value" "1K4R2F-1-GP"
			(at 0.064008 -3.993896 270)
			(unlocked yes)
			(layer "F.Fab")
			(hide yes)
			(effects
				(font
					(size 1.016 1.016)
					(thickness 0.1524)
				)
			)
		)
		(property "Device Type" "R402H16"
			(at 0.064008 -5.517896 270)
			(unlocked yes)
			(layer "F.Fab")
			(hide yes)
			(effects
				(font
					(size 1.016 1.016)
					(thickness 0.1524)
				)
			)
		)
		(duplicate_pad_numbers_are_jumpers no)
		(fp_line
			(start -0.508 -0.9398)
			(end -0.508 0.9398)
			(stroke
				(width 0.1524)
				(type default)
			)
			(layer "F.SilkS")
		)
		(fp_line
			(start 0.508 -0.9398)
			(end -0.508 -0.9398)
			(stroke
				(width 0.1524)
				(type default)
			)
			(layer "F.SilkS")
		)
		(fp_rect
			(start -0.508 0.9398)
			(end 0.508 -0.9398)
			(stroke
				(width 0)
				(type default)
			)
			(fill no)
			(layer "F.CrtYd")
		)
		(fp_rect
			(start -0.508 0.9398)
			(end 0.508 -0.9398)
			(stroke
				(width 0)
				(type default)
			)
			(fill no)
			(layer "F.Fab")
		)
		(pad "1" smd custom
			(at 0 -0.4445 270)
			(size 0.1397 0.1397)
			(layers "F.Cu" "F.Mask" "F.Paste")
			(net "CLK_BUF_EU3_HIBW_BYPM_LOBW#")
			(options
				(clearance outline)
				(anchor circle)
			)
			(primitives
				(gr_poly
					(pts
						(arc
							(start -0.1778 -0.2794)
							(mid -0.249642 -0.249642)
							(end -0.2794 -0.1778)
						)
						(arc
							(start -0.2794 0.1778)
							(mid -0.249642 0.249642)
							(end -0.1778 0.2794)
						)
						(arc
							(start 0.1778 0.2794)
							(mid 0.249642 0.249642)
							(end 0.2794 0.1778)
						)
						(arc
							(start 0.2794 -0.1778)
							(mid 0.249642 -0.249642)
							(end 0.1778 -0.2794)
						)
					)
					(width 0)
					(fill yes)
				)
			)
		)
		(pad "2" smd custom
			(at 0 0.4445 270)
			(size 0.1397 0.1397)
			(layers "F.Cu" "F.Mask" "F.Paste")
			(net "GND")
			(options
				(clearance outline)
				(anchor circle)
			)
			(primitives
				(gr_poly
					(pts
						(arc
							(start -0.1778 -0.2794)
							(mid -0.249642 -0.249642)
							(end -0.2794 -0.1778)
						)
						(arc
							(start -0.2794 0.1778)
							(mid -0.249642 0.249642)
							(end -0.1778 0.2794)
						)
						(arc
							(start 0.1778 0.2794)
							(mid 0.249642 0.249642)
							(end 0.2794 0.1778)
						)
						(arc
							(start 0.2794 -0.1778)
							(mid 0.249642 -0.249642)
							(end 0.1778 -0.2794)
						)
					)
					(width 0)
					(fill yes)
				)
			)
		)
	)
)
